# SDI-MIPI Bridge — symbol library table
(sym_lib_table
  (lib (name "sdi-mipi-bridge")(type "KiCad")(uri "${KIPRJMOD}/lib/sdi-mipi-bridge.kicad_sym")(options "")(descr ""))
)
